# S9S_MB_2U (Grand Teton) — schematic netlist excerpt (pin names and nets, part order shuffled) for the footprints in the layout excerpt that follows; sources: Cadence DE-HDL packaged netlist, KiCad conversion of 03242023_DA0F0TMBIJ0_F0T_Motherboard_J_brd_V01_OCP.brd

PC239_P0_7  Q_CAP  22UF 16V 20% X6S  pkg C0805  page 270 : A = SW_P12V_PVCCIN_CPU0_FLT ; B = GND
R56  Q_RES  0 5% CHIP  pkg 0402LF  page 45 : A = SVID_CLK0_CPU1 ; B = SVID_CLK0_CPU1_R
PC205_P0_2  Q_CAP  22UF 4V 20% X6S  pkg C0805  page 275 : A = PVCCINFAON_CPU0 ; B = GND

(kicad_pcb
	(version 20260206)
	(generator "pcbnew")
	(generator_version "10.0")
	(general
		(thickness 1.6)
		(legacy_teardrops no)
	)
	(paper "A4")
	(title_block
		(title "03242023_DA0F0TMBIJ0_F0T_Motherboard_J_brd_V01_OCP.brd")
		(comment 1 "Grand Teton / footprints 5662-5664 of 6105")
	)
	(layers
		(0 "F.Cu" signal "TOP")
		(4 "In1.Cu" signal "GND")
		(6 "In2.Cu" signal "IN1")
		(8 "In3.Cu" signal "GND1")
		(10 "In4.Cu" signal "IN2")
		(12 "In5.Cu" signal "GND2")
		(14 "In6.Cu" signal "IN3")
		(16 "In7.Cu" signal "GND3")
		(18 "In8.Cu" signal "VCC")
		(20 "In9.Cu" signal "VCC1")
		(22 "In10.Cu" signal "GND4")
		(24 "In11.Cu" signal "IN4")
		(26 "In12.Cu" signal "GND5")
		(28 "In13.Cu" signal "IN5")
		(30 "In14.Cu" signal "GND6")
		(32 "In15.Cu" signal "IN6")
		(34 "In16.Cu" signal "GND7")
		(2 "B.Cu" signal "BOTTOM")
		(9 "F.Adhes" user "F.Adhesive")
		(11 "B.Adhes" user "B.Adhesive")
		(13 "F.Paste" user "Package Geometry/Pastemask Top")
		(15 "B.Paste" user "Package Geometry/Pastemask Bottom")
		(5 "F.SilkS" user "Ref Des/Silkscreen Top")
		(7 "B.SilkS" user "Ref Des/Silkscreen Bottom")
		(1 "F.Mask" user "Board Geometry/Soldermask Top")
		(3 "B.Mask" user "Board Geometry/Soldermask Bottom")
		(17 "Dwgs.User" user "User.Drawings")
		(19 "Cmts.User" user "User.Comments")
		(21 "Eco1.User" user "User.Eco1")
		(23 "Eco2.User" user "User.Eco2")
		(25 "Edge.Cuts" user "Board Geometry/Outline")
		(27 "Margin" user)
		(31 "F.CrtYd" user "Package Geometry/Place Bound Top")
		(29 "B.CrtYd" user "Package Geometry/Place Bound Bottom")
		(35 "F.Fab" user "Ref Des/Assembly Top")
		(33 "B.Fab" user "Ref Des/Assembly Bottom")
	)
	(footprint ""
		(layer "B.Cu")
		(at 71.385684 -190.744856 90)
		(property "Reference" "R56"
			(at 0 0 90)
			(layer "B.SilkS")
			(hide yes)
			(effects
				(font
					(size 1.27 1.27)
				)
				(justify mirror)
			)
		)
		(property "Value" ""
			(at 0 0 90)
			(layer "B.Fab")
			(effects
				(font
					(size 1.27 1.27)
				)
				(justify mirror)
			)
		)
		(duplicate_pad_numbers_are_jumpers no)
		(fp_line
			(start 0.7874 -0.4064)
			(end -0.7874 -0.4064)
			(stroke
				(width 0.1524)
				(type default)
			)
			(layer "B.SilkS")
		)
		(fp_line
			(start -0.7874 -0.4064)
			(end -0.7874 0.4064)
			(stroke
				(width 0.1524)
				(type default)
			)
			(layer "B.SilkS")
		)
		(fp_line
			(start 0.7874 0.4064)
			(end 0.7874 -0.4064)
			(stroke
				(width 0.1524)
				(type default)
			)
			(layer "B.SilkS")
		)
		(fp_line
			(start -0.7874 0.4064)
			(end 0.7874 0.4064)
			(stroke
				(width 0.1524)
				(type default)
			)
			(layer "B.SilkS")
		)
		(fp_line
			(start 0.67945 -0.305054)
			(end 0.12065 -0.305054)
			(stroke
				(width 0.1)
				(type default)
			)
			(layer "B.Fab")
		)
		(fp_line
			(start 0.12065 -0.305054)
			(end 0.12065 -0.2794)
			(stroke
				(width 0.1)
				(type default)
			)
			(layer "B.Fab")
		)
		(fp_line
			(start -0.12065 -0.3048)
			(end -0.67945 -0.3048)
			(stroke
				(width 0.1)
				(type default)
			)
			(layer "B.Fab")
		)
		(fp_line
			(start -0.67945 -0.3048)
			(end -0.67945 0.3048)
			(stroke
				(width 0.1)
				(type default)
			)
			(layer "B.Fab")
		)
		(fp_line
			(start 0.12065 -0.2794)
			(end -0.12065 -0.2794)
			(stroke
				(width 0.1)
				(type default)
			)
			(layer "B.Fab")
		)
		(fp_line
			(start -0.12065 -0.2794)
			(end -0.12065 -0.3048)
			(stroke
				(width 0.1)
				(type default)
			)
			(layer "B.Fab")
		)
		(fp_line
			(start 0.12065 0.2794)
			(end 0.12065 0.3048)
			(stroke
				(width 0.1)
				(type default)
			)
			(layer "B.Fab")
		)
		(fp_line
			(start -0.120396 0.2794)
			(end 0.12065 0.2794)
			(stroke
				(width 0.1)
				(type default)
			)
			(layer "B.Fab")
		)
		(fp_line
			(start 0.67945 0.3048)
			(end 0.67945 -0.305054)
			(stroke
				(width 0.1)
				(type default)
			)
			(layer "B.Fab")
		)
		(fp_line
			(start 0.12065 0.3048)
			(end 0.67945 0.3048)
			(stroke
				(width 0.1)
				(type default)
			)
			(layer "B.Fab")
		)
		(fp_line
			(start -0.120396 0.3048)
			(end -0.120396 0.2794)
			(stroke
				(width 0.1)
				(type default)
			)
			(layer "B.Fab")
		)
		(fp_line
			(start -0.67945 0.3048)
			(end -0.120396 0.3048)
			(stroke
				(width 0.1)
				(type default)
			)
			(layer "B.Fab")
		)
		(pad "1" smd circle
			(at 0.40005 0 270)
			(size 0 0)
			(layers "B.Cu" "B.Mask" "B.Paste")
			(net "SVID_CLK0_CPU1")
		)
		(pad "2" smd circle
			(at -0.40005 0 270)
			(size 0 0)
			(layers "B.Cu" "B.Mask" "B.Paste")
			(net "SVID_CLK0_CPU1_R")
		)
	)
	(footprint ""
		(layer "B.Cu")
		(at 330.11999 -346.808298 -90)
		(property "Reference" "PC239_P0_7"
			(at 0 0 90)
			(layer "B.SilkS")
			(hide yes)
			(effects
				(font
					(size 1.27 1.27)
				)
				(justify mirror)
			)
		)
		(property "Value" ""
			(at 0 0 90)
			(layer "B.Fab")
			(effects
				(font
					(size 1.27 1.27)
				)
				(justify mirror)
			)
		)
		(duplicate_pad_numbers_are_jumpers no)
		(fp_line
			(start -1.524 0.762)
			(end 1.524 0.762)
			(stroke
				(width 0.1524)
				(type default)
			)
			(layer "B.SilkS")
		)
		(fp_line
			(start 1.524 0.762)
			(end 1.524 -0.762)
			(stroke
				(width 0.1524)
				(type default)
			)
			(layer "B.SilkS")
		)
		(fp_line
			(start -1.524 -0.762)
			(end -1.524 0.762)
			(stroke
				(width 0.1524)
				(type default)
			)
			(layer "B.SilkS")
		)
		(fp_line
			(start 1.524 -0.762)
			(end -1.524 -0.762)
			(stroke
				(width 0.1524)
				(type default)
			)
			(layer "B.SilkS")
		)
		(fp_line
			(start -1.1049 0.724916)
			(end -1.1049 -0.724916)
			(stroke
				(width 0.1)
				(type default)
			)
			(layer "B.Fab")
		)
		(fp_line
			(start 1.1049 0.724916)
			(end -1.1049 0.724916)
			(stroke
				(width 0.1)
				(type default)
			)
			(layer "B.Fab")
		)
		(fp_line
			(start -1.1049 -0.724916)
			(end 1.1049 -0.724916)
			(stroke
				(width 0.1)
				(type default)
			)
			(layer "B.Fab")
		)
		(fp_line
			(start 1.1049 -0.724916)
			(end 1.1049 0.724916)
			(stroke
				(width 0.1)
				(type default)
			)
			(layer "B.Fab")
		)
		(pad "1" smd rect
			(at 0.889 0 270)
			(size 1.016 1.27)
			(layers "B.Cu" "B.Mask" "B.Paste")
			(net "SW_P12V_PVCCIN_CPU0_FLT")
		)
		(pad "2" smd rect
			(at -0.889 0 270)
			(size 1.016 1.27)
			(layers "B.Cu" "B.Mask" "B.Paste")
			(net "GND")
		)
	)
	(footprint ""
		(layer "B.Cu")
		(at 407.91257 -182.776368 180)
		(property "Reference" "PC205_P0_2"
			(at 0 0 0)
			(layer "B.SilkS")
			(hide yes)
			(effects
				(font
					(size 1.27 1.27)
				)
				(justify mirror)
			)
		)
		(property "Value" ""
			(at 0 0 0)
			(layer "B.Fab")
			(effects
				(font
					(size 1.27 1.27)
				)
				(justify mirror)
			)
		)
		(duplicate_pad_numbers_are_jumpers no)
		(fp_line
			(start 1.524 0.762)
			(end 1.524 -0.762)
			(stroke
				(width 0.1524)
				(type default)
			)
			(layer "B.SilkS")
		)
		(fp_line
			(start 1.524 -0.762)
			(end -1.524 -0.762)
			(stroke
				(width 0.1524)
				(type default)
			)
			(layer "B.SilkS")
		)
		(fp_line
			(start -1.524 0.762)
			(end 1.524 0.762)
			(stroke
				(width 0.1524)
				(type default)
			)
			(layer "B.SilkS")
		)
		(fp_line
			(start -1.524 -0.762)
			(end -1.524 0.762)
			(stroke
				(width 0.1524)
				(type default)
			)
			(layer "B.SilkS")
		)
		(fp_line
			(start 1.1049 0.724916)
			(end -1.1049 0.724916)
			(stroke
				(width 0.1)
				(type default)
			)
			(layer "B.Fab")
		)
		(fp_line
			(start 1.1049 -0.724916)
			(end 1.1049 0.724916)
			(stroke
				(width 0.1)
				(type default)
			)
			(layer "B.Fab")
		)
		(fp_line
			(start -1.1049 0.724916)
			(end -1.1049 -0.724916)
			(stroke
				(width 0.1)
				(type default)
			)
			(layer "B.Fab")
		)
		(fp_line
			(start -1.1049 -0.724916)
			(end 1.1049 -0.724916)
			(stroke
				(width 0.1)
				(type default)
			)
			(layer "B.Fab")
		)
		(pad "1" smd rect
			(at 0.889 0 180)
			(size 1.016 1.27)
			(layers "B.Cu" "B.Mask" "B.Paste")
			(net "PVCCINFAON_CPU0")
		)
		(pad "2" smd rect
			(at -0.889 0 180)
			(size 1.016 1.27)
			(layers "B.Cu" "B.Mask" "B.Paste")
			(net "GND")
		)
	)
)
